(kicad_pcb
	(version 20260206)
	(generator "pcbnew")
	(generator_version "10.0")
	(general
		(thickness 1.6)
		(legacy_teardrops no)
	)
	(paper "A4")
	(title_block
		(title "03242023_DA0F0TMBIJ0_F0T_Motherboard_J_brd_V01_OCP.brd")
		(comment 1 "Grand Teton / footprints 2993-3000 of 6105")
	)
	(layers
		(0 "F.Cu" signal "TOP")
		(4 "In1.Cu" signal "GND")
		(6 "In2.Cu" signal "IN1")
		(8 "In3.Cu" signal "GND1")
		(10 "In4.Cu" signal "IN2")
		(12 "In5.Cu" signal "GND2")
		(14 "In6.Cu" signal "IN3")
		(16 "In7.Cu" signal "GND3")
		(18 "In8.Cu" signal "VCC")
		(20 "In9.Cu" signal "VCC1")
		(22 "In10.Cu" signal "GND4")
		(24 "In11.Cu" signal "IN4")
		(26 "In12.Cu" signal "GND5")
		(28 "In13.Cu" signal "IN5")
		(30 "In14.Cu" signal "GND6")
		(32 "In15.Cu" signal "IN6")
		(34 "In16.Cu" signal "GND7")
		(2 "B.Cu" signal "BOTTOM")
		(9 "F.Adhes" user "F.Adhesive")
		(11 "B.Adhes" user "B.Adhesive")
		(13 "F.Paste" user "Package Geometry/Pastemask Top")
		(15 "B.Paste" user "Package Geometry/Pastemask Bottom")
		(5 "F.SilkS" user "Ref Des/Silkscreen Top")
		(7 "B.SilkS" user "Ref Des/Silkscreen Bottom")
		(1 "F.Mask" user "Board Geometry/Soldermask Top")
		(3 "B.Mask" user "Board Geometry/Soldermask Bottom")
		(17 "Dwgs.User" user "User.Drawings")
		(19 "Cmts.User" user "User.Comments")
		(21 "Eco1.User" user "User.Eco1")
		(23 "Eco2.User" user "User.Eco2")
		(25 "Edge.Cuts" user "Board Geometry/Outline")
		(27 "Margin" user)
		(31 "F.CrtYd" user "Package Geometry/Place Bound Top")
		(29 "B.CrtYd" user "Package Geometry/Place Bound Bottom")
		(35 "F.Fab" user "Ref Des/Assembly Top")
		(33 "B.Fab" user "Ref Des/Assembly Bottom")
	)
	(footprint ""
		(layer "F.Cu")
		(at 455.439526 -99.124008)
		(property "Reference" "R1719"
			(at 0 0 0)
			(layer "F.SilkS")
			(hide yes)
			(effects
				(font
					(size 1.27 1.27)
				)
			)
		)
		(property "Value" ""
			(at 0 0 0)
			(layer "F.Fab")
			(effects
				(font
					(size 1.27 1.27)
				)
			)
		)
		(duplicate_pad_numbers_are_jumpers no)
		(fp_line
			(start -0.7874 -0.4064)
			(end 0.7874 -0.4064)
			(stroke
				(width 0.1524)
				(type default)
			)
			(layer "F.SilkS")
		)
		(fp_line
			(start -0.7874 0.4064)
			(end -0.7874 -0.4064)
			(stroke
				(width 0.1524)
				(type default)
			)
			(layer "F.SilkS")
		)
		(fp_line
			(start 0.7874 -0.4064)
			(end 0.7874 0.4064)
			(stroke
				(width 0.1524)
				(type default)
			)
			(layer "F.SilkS")
		)
		(fp_line
			(start 0.7874 0.4064)
			(end -0.7874 0.4064)
			(stroke
				(width 0.1524)
				(type default)
			)
			(layer "F.SilkS")
		)
		(fp_line
			(start -0.67945 -0.305054)
			(end -0.12065 -0.305054)
			(stroke
				(width 0.1)
				(type default)
			)
			(layer "F.Fab")
		)
		(fp_line
			(start -0.67945 0.3048)
			(end -0.67945 -0.305054)
			(stroke
				(width 0.1)
				(type default)
			)
			(layer "F.Fab")
		)
		(fp_line
			(start -0.12065 -0.305054)
			(end -0.12065 -0.2794)
			(stroke
				(width 0.1)
				(type default)
			)
			(layer "F.Fab")
		)
		(fp_line
			(start -0.12065 -0.2794)
			(end 0.12065 -0.2794)
			(stroke
				(width 0.1)
				(type default)
			)
			(layer "F.Fab")
		)
		(fp_line
			(start -0.12065 0.2794)
			(end -0.12065 0.3048)
			(stroke
				(width 0.1)
				(type default)
			)
			(layer "F.Fab")
		)
		(fp_line
			(start -0.12065 0.3048)
			(end -0.67945 0.3048)
			(stroke
				(width 0.1)
				(type default)
			)
			(layer "F.Fab")
		)
		(fp_line
			(start 0.120396 0.2794)
			(end -0.12065 0.2794)
			(stroke
				(width 0.1)
				(type default)
			)
			(layer "F.Fab")
		)
		(fp_line
			(start 0.120396 0.3048)
			(end 0.120396 0.2794)
			(stroke
				(width 0.1)
				(type default)
			)
			(layer "F.Fab")
		)
		(fp_line
			(start 0.12065 -0.3048)
			(end 0.67945 -0.3048)
			(stroke
				(width 0.1)
				(type default)
			)
			(layer "F.Fab")
		)
		(fp_line
			(start 0.12065 -0.2794)
			(end 0.12065 -0.3048)
			(stroke
				(width 0.1)
				(type default)
			)
			(layer "F.Fab")
		)
		(fp_line
			(start 0.67945 -0.3048)
			(end 0.67945 0.3048)
			(stroke
				(width 0.1)
				(type default)
			)
			(layer "F.Fab")
		)
		(fp_line
			(start 0.67945 0.3048)
			(end 0.120396 0.3048)
			(stroke
				(width 0.1)
				(type default)
			)
			(layer "F.Fab")
		)
		(pad "1" smd circle
			(at -0.40005 0)
			(size 0 0)
			(layers "F.Cu" "F.Mask" "F.Paste")
			(net "OCP_SFF_AUX_PWR_EN")
		)
		(pad "2" smd circle
			(at 0.40005 0)
			(size 0 0)
			(layers "F.Cu" "F.Mask" "F.Paste")
			(net "OCP_SFF_AUX_PWR_EN_R1")
		)
	)
	(footprint ""
		(layer "F.Cu")
		(at 437.425846 -383.51968 180)
		(property "Reference" "PC1855"
			(at 0 0 180)
			(layer "F.SilkS")
			(hide yes)
			(effects
				(font
					(size 1.27 1.27)
				)
			)
		)
		(property "Value" ""
			(at 0 0 180)
			(layer "F.Fab")
			(effects
				(font
					(size 1.27 1.27)
				)
			)
		)
		(duplicate_pad_numbers_are_jumpers no)
		(fp_line
			(start 1.524 0.762)
			(end -1.524 0.762)
			(stroke
				(width 0.1524)
				(type default)
			)
			(layer "F.SilkS")
		)
		(fp_line
			(start 1.524 -0.762)
			(end 1.524 0.762)
			(stroke
				(width 0.1524)
				(type default)
			)
			(layer "F.SilkS")
		)
		(fp_line
			(start -1.524 0.762)
			(end -1.524 -0.762)
			(stroke
				(width 0.1524)
				(type default)
			)
			(layer "F.SilkS")
		)
		(fp_line
			(start -1.524 -0.762)
			(end 1.524 -0.762)
			(stroke
				(width 0.1524)
				(type default)
			)
			(layer "F.SilkS")
		)
		(fp_line
			(start 1.1049 0.724916)
			(end 1.1049 -0.724916)
			(stroke
				(width 0.1)
				(type default)
			)
			(layer "F.Fab")
		)
		(fp_line
			(start 1.1049 -0.724916)
			(end -1.1049 -0.724916)
			(stroke
				(width 0.1)
				(type default)
			)
			(layer "F.Fab")
		)
		(fp_line
			(start -1.1049 0.724916)
			(end 1.1049 0.724916)
			(stroke
				(width 0.1)
				(type default)
			)
			(layer "F.Fab")
		)
		(fp_line
			(start -1.1049 -0.724916)
			(end -1.1049 0.724916)
			(stroke
				(width 0.1)
				(type default)
			)
			(layer "F.Fab")
		)
		(pad "1" smd rect
			(at -0.889 0)
			(size 1.016 1.27)
			(layers "F.Cu" "F.Mask" "F.Paste")
			(net "P5V_AUX")
		)
		(pad "2" smd rect
			(at 0.889 0)
			(size 1.016 1.27)
			(layers "F.Cu" "F.Mask" "F.Paste")
			(net "GND")
		)
	)
	(footprint ""
		(layer "F.Cu")
		(at 406.00757 -402.371052 -90)
		(property "Reference" "C956"
			(at 0 0 270)
			(layer "F.SilkS")
			(hide yes)
			(effects
				(font
					(size 1.27 1.27)
				)
			)
		)
		(property "Value" ""
			(at 0 0 270)
			(layer "F.Fab")
			(effects
				(font
					(size 1.27 1.27)
				)
			)
		)
		(duplicate_pad_numbers_are_jumpers no)
		(fp_line
			(start -0.299974 0.150114)
			(end -0.299974 -0.150114)
			(stroke
				(width 0.1)
				(type default)
			)
			(layer "F.Fab")
		)
		(fp_line
			(start 0.299974 0.150114)
			(end -0.299974 0.150114)
			(stroke
				(width 0.1)
				(type default)
			)
			(layer "F.Fab")
		)
		(fp_line
			(start -0.299974 -0.150114)
			(end 0.299974 -0.150114)
			(stroke
				(width 0.1)
				(type default)
			)
			(layer "F.Fab")
		)
		(fp_line
			(start 0.299974 -0.150114)
			(end 0.299974 0.150114)
			(stroke
				(width 0.1)
				(type default)
			)
			(layer "F.Fab")
		)
		(pad "1" smd rect
			(at -0.2667 0 270)
			(size 0.3048 0.381)
			(layers "F.Cu" "F.Mask" "F.Paste")
			(net "P5E_CPU0_PE2_TX_C_DN<4>")
		)
		(pad "2" smd rect
			(at 0.2667 0 270)
			(size 0.3048 0.381)
			(layers "F.Cu" "F.Mask" "F.Paste")
			(net "P5E_CPU0_PE2_TX_DN<4>")
		)
	)
	(footprint ""
		(layer "F.Cu")
		(at 109.744002 -336.192368 90)
		(property "Reference" "PC524"
			(at 0 0 90)
			(layer "F.SilkS")
			(hide yes)
			(effects
				(font
					(size 1.27 1.27)
				)
			)
		)
		(property "Value" ""
			(at 0 0 90)
			(layer "F.Fab")
			(effects
				(font
					(size 1.27 1.27)
				)
			)
		)
		(duplicate_pad_numbers_are_jumpers no)
		(fp_line
			(start 0.7874 -0.4064)
			(end 0.7874 0.4064)
			(stroke
				(width 0.1524)
				(type default)
			)
			(layer "F.SilkS")
		)
		(fp_line
			(start -0.7874 -0.4064)
			(end 0.7874 -0.4064)
			(stroke
				(width 0.1524)
				(type default)
			)
			(layer "F.SilkS")
		)
		(fp_line
			(start 0.7874 0.4064)
			(end -0.7874 0.4064)
			(stroke
				(width 0.1524)
				(type default)
			)
			(layer "F.SilkS")
		)
		(fp_line
			(start -0.7874 0.4064)
			(end -0.7874 -0.4064)
			(stroke
				(width 0.1524)
				(type default)
			)
			(layer "F.SilkS")
		)
		(fp_line
			(start -0.12065 -0.305054)
			(end -0.12065 -0.2794)
			(stroke
				(width 0.1)
				(type default)
			)
			(layer "F.Fab")
		)
		(fp_line
			(start -0.67945 -0.305054)
			(end -0.12065 -0.305054)
			(stroke
				(width 0.1)
				(type default)
			)
			(layer "F.Fab")
		)
		(fp_line
			(start 0.67945 -0.3048)
			(end 0.67945 0.3048)
			(stroke
				(width 0.1)
				(type default)
			)
			(layer "F.Fab")
		)
		(fp_line
			(start 0.12065 -0.3048)
			(end 0.67945 -0.3048)
			(stroke
				(width 0.1)
				(type default)
			)
			(layer "F.Fab")
		)
		(fp_line
			(start 0.12065 -0.2794)
			(end 0.12065 -0.3048)
			(stroke
				(width 0.1)
				(type default)
			)
			(layer "F.Fab")
		)
		(fp_line
			(start -0.12065 -0.2794)
			(end 0.12065 -0.2794)
			(stroke
				(width 0.1)
				(type default)
			)
			(layer "F.Fab")
		)
		(fp_line
			(start 0.120396 0.2794)
			(end -0.12065 0.2794)
			(stroke
				(width 0.1)
				(type default)
			)
			(layer "F.Fab")
		)
		(fp_line
			(start -0.12065 0.2794)
			(end -0.12065 0.3048)
			(stroke
				(width 0.1)
				(type default)
			)
			(layer "F.Fab")
		)
		(fp_line
			(start 0.67945 0.3048)
			(end 0.120396 0.3048)
			(stroke
				(width 0.1)
				(type default)
			)
			(layer "F.Fab")
		)
		(fp_line
			(start 0.120396 0.3048)
			(end 0.120396 0.2794)
			(stroke
				(width 0.1)
				(type default)
			)
			(layer "F.Fab")
		)
		(fp_line
			(start -0.12065 0.3048)
			(end -0.67945 0.3048)
			(stroke
				(width 0.1)
				(type default)
			)
			(layer "F.Fab")
		)
		(fp_line
			(start -0.67945 0.3048)
			(end -0.67945 -0.305054)
			(stroke
				(width 0.1)
				(type default)
			)
			(layer "F.Fab")
		)
		(pad "1" smd circle
			(at -0.40005 0 90)
			(size 0 0)
			(layers "F.Cu" "F.Mask" "F.Paste")
			(net "PVCCIN_CPU1_VDD3")
		)
		(pad "2" smd circle
			(at 0.40005 0 90)
			(size 0 0)
			(layers "F.Cu" "F.Mask" "F.Paste")
			(net "GND")
		)
	)
	(footprint ""
		(layer "F.Cu")
		(at 161.297874 -408.517344 -90)
		(property "Reference" "C1542"
			(at 0 0 270)
			(layer "F.SilkS")
			(hide yes)
			(effects
				(font
					(size 1.27 1.27)
				)
			)
		)
		(property "Value" ""
			(at 0 0 270)
			(layer "F.Fab")
			(effects
				(font
					(size 1.27 1.27)
				)
			)
		)
		(duplicate_pad_numbers_are_jumpers no)
		(fp_line
			(start -0.299974 0.150114)
			(end -0.299974 -0.150114)
			(stroke
				(width 0.1)
				(type default)
			)
			(layer "F.Fab")
		)
		(fp_line
			(start 0.299974 0.150114)
			(end -0.299974 0.150114)
			(stroke
				(width 0.1)
				(type default)
			)
			(layer "F.Fab")
		)
		(fp_line
			(start -0.299974 -0.150114)
			(end 0.299974 -0.150114)
			(stroke
				(width 0.1)
				(type default)
			)
			(layer "F.Fab")
		)
		(fp_line
			(start 0.299974 -0.150114)
			(end 0.299974 0.150114)
			(stroke
				(width 0.1)
				(type default)
			)
			(layer "F.Fab")
		)
		(pad "1" smd rect
			(at -0.2667 0 270)
			(size 0.3048 0.381)
			(layers "F.Cu" "F.Mask" "F.Paste")
			(net "P5E_CPU1_PE3_TX_C_DN<2>")
		)
		(pad "2" smd rect
			(at 0.2667 0 270)
			(size 0.3048 0.381)
			(layers "F.Cu" "F.Mask" "F.Paste")
			(net "P5E_CPU1_PE3_TX_DN<2>")
		)
	)
	(footprint ""
		(layer "F.Cu")
		(at 136.61136 -25.189688 180)
		(property "Reference" "R4275"
			(at 0 0 180)
			(layer "F.SilkS")
			(hide yes)
			(effects
				(font
					(size 1.27 1.27)
				)
			)
		)
		(property "Value" ""
			(at 0 0 180)
			(layer "F.Fab")
			(effects
				(font
					(size 1.27 1.27)
				)
			)
		)
		(duplicate_pad_numbers_are_jumpers no)
		(fp_line
			(start 0.7874 0.4064)
			(end -0.7874 0.4064)
			(stroke
				(width 0.1524)
				(type default)
			)
			(layer "F.SilkS")
		)
		(fp_line
			(start 0.7874 -0.4064)
			(end 0.7874 0.4064)
			(stroke
				(width 0.1524)
				(type default)
			)
			(layer "F.SilkS")
		)
		(fp_line
			(start -0.7874 0.4064)
			(end -0.7874 -0.4064)
			(stroke
				(width 0.1524)
				(type default)
			)
			(layer "F.SilkS")
		)
		(fp_line
			(start -0.7874 -0.4064)
			(end 0.7874 -0.4064)
			(stroke
				(width 0.1524)
				(type default)
			)
			(layer "F.SilkS")
		)
		(fp_line
			(start 0.67945 0.3048)
			(end 0.120396 0.3048)
			(stroke
				(width 0.1)
				(type default)
			)
			(layer "F.Fab")
		)
		(fp_line
			(start 0.67945 -0.3048)
			(end 0.67945 0.3048)
			(stroke
				(width 0.1)
				(type default)
			)
			(layer "F.Fab")
		)
		(fp_line
			(start 0.12065 -0.2794)
			(end 0.12065 -0.3048)
			(stroke
				(width 0.1)
				(type default)
			)
			(layer "F.Fab")
		)
		(fp_line
			(start 0.12065 -0.3048)
			(end 0.67945 -0.3048)
			(stroke
				(width 0.1)
				(type default)
			)
			(layer "F.Fab")
		)
		(fp_line
			(start 0.120396 0.3048)
			(end 0.120396 0.2794)
			(stroke
				(width 0.1)
				(type default)
			)
			(layer "F.Fab")
		)
		(fp_line
			(start 0.120396 0.2794)
			(end -0.12065 0.2794)
			(stroke
				(width 0.1)
				(type default)
			)
			(layer "F.Fab")
		)
		(fp_line
			(start -0.12065 0.3048)
			(end -0.67945 0.3048)
			(stroke
				(width 0.1)
				(type default)
			)
			(layer "F.Fab")
		)
		(fp_line
			(start -0.12065 0.2794)
			(end -0.12065 0.3048)
			(stroke
				(width 0.1)
				(type default)
			)
			(layer "F.Fab")
		)
		(fp_line
			(start -0.12065 -0.2794)
			(end 0.12065 -0.2794)
			(stroke
				(width 0.1)
				(type default)
			)
			(layer "F.Fab")
		)
		(fp_line
			(start -0.12065 -0.305054)
			(end -0.12065 -0.2794)
			(stroke
				(width 0.1)
				(type default)
			)
			(layer "F.Fab")
		)
		(fp_line
			(start -0.67945 0.3048)
			(end -0.67945 -0.305054)
			(stroke
				(width 0.1)
				(type default)
			)
			(layer "F.Fab")
		)
		(fp_line
			(start -0.67945 -0.305054)
			(end -0.12065 -0.305054)
			(stroke
				(width 0.1)
				(type default)
			)
			(layer "F.Fab")
		)
		(pad "1" smd circle
			(at -0.40005 0 180)
			(size 0 0)
			(layers "F.Cu" "F.Mask" "F.Paste")
			(net "P3V3_AUX")
		)
		(pad "2" smd circle
			(at 0.40005 0 180)
			(size 0 0)
			(layers "F.Cu" "F.Mask" "F.Paste")
			(net "FM_USB3_1_EQA")
		)
	)
	(footprint ""
		(layer "F.Cu")
		(at 366.413542 -420.108126 -90)
		(property "Reference" "R4212"
			(at 0 0 270)
			(layer "F.SilkS")
			(hide yes)
			(effects
				(font
					(size 1.27 1.27)
				)
			)
		)
		(property "Value" ""
			(at 0 0 270)
			(layer "F.Fab")
			(effects
				(font
					(size 1.27 1.27)
				)
			)
		)
		(duplicate_pad_numbers_are_jumpers no)
		(fp_line
			(start -0.7874 0.4064)
			(end -0.7874 -0.4064)
			(stroke
				(width 0.1524)
				(type default)
			)
			(layer "F.SilkS")
		)
		(fp_line
			(start 0.7874 0.4064)
			(end -0.7874 0.4064)
			(stroke
				(width 0.1524)
				(type default)
			)
			(layer "F.SilkS")
		)
		(fp_line
			(start -0.7874 -0.4064)
			(end 0.7874 -0.4064)
			(stroke
				(width 0.1524)
				(type default)
			)
			(layer "F.SilkS")
		)
		(fp_line
			(start 0.7874 -0.4064)
			(end 0.7874 0.4064)
			(stroke
				(width 0.1524)
				(type default)
			)
			(layer "F.SilkS")
		)
		(fp_line
			(start -0.67945 0.3048)
			(end -0.67945 -0.305054)
			(stroke
				(width 0.1)
				(type default)
			)
			(layer "F.Fab")
		)
		(fp_line
			(start -0.12065 0.3048)
			(end -0.67945 0.3048)
			(stroke
				(width 0.1)
				(type default)
			)
			(layer "F.Fab")
		)
		(fp_line
			(start 0.120396 0.3048)
			(end 0.120396 0.2794)
			(stroke
				(width 0.1)
				(type default)
			)
			(layer "F.Fab")
		)
		(fp_line
			(start 0.67945 0.3048)
			(end 0.120396 0.3048)
			(stroke
				(width 0.1)
				(type default)
			)
			(layer "F.Fab")
		)
		(fp_line
			(start -0.12065 0.2794)
			(end -0.12065 0.3048)
			(stroke
				(width 0.1)
				(type default)
			)
			(layer "F.Fab")
		)
		(fp_line
			(start 0.120396 0.2794)
			(end -0.12065 0.2794)
			(stroke
				(width 0.1)
				(type default)
			)
			(layer "F.Fab")
		)
		(fp_line
			(start -0.12065 -0.2794)
			(end 0.12065 -0.2794)
			(stroke
				(width 0.1)
				(type default)
			)
			(layer "F.Fab")
		)
		(fp_line
			(start 0.12065 -0.2794)
			(end 0.12065 -0.3048)
			(stroke
				(width 0.1)
				(type default)
			)
			(layer "F.Fab")
		)
		(fp_line
			(start 0.12065 -0.3048)
			(end 0.67945 -0.3048)
			(stroke
				(width 0.1)
				(type default)
			)
			(layer "F.Fab")
		)
		(fp_line
			(start 0.67945 -0.3048)
			(end 0.67945 0.3048)
			(stroke
				(width 0.1)
				(type default)
			)
			(layer "F.Fab")
		)
		(fp_line
			(start -0.67945 -0.305054)
			(end -0.12065 -0.305054)
			(stroke
				(width 0.1)
				(type default)
			)
			(layer "F.Fab")
		)
		(fp_line
			(start -0.12065 -0.305054)
			(end -0.12065 -0.2794)
			(stroke
				(width 0.1)
				(type default)
			)
			(layer "F.Fab")
		)
		(pad "1" smd circle
			(at -0.40005 0 270)
			(size 0 0)
			(layers "F.Cu" "F.Mask" "F.Paste")
			(net "FM_THERMAL_ALERT_N")
		)
		(pad "2" smd circle
			(at 0.40005 0 270)
			(size 0 0)
			(layers "F.Cu" "F.Mask" "F.Paste")
			(net "FM_LM75_3_ALERT_N")
		)
	)
	(footprint ""
		(layer "F.Cu")
		(at 346.037408 -408.517344 -90)
		(property "Reference" "C929"
			(at 0 0 270)
			(layer "F.SilkS")
			(hide yes)
			(effects
				(font
					(size 1.27 1.27)
				)
			)
		)
		(property "Value" ""
			(at 0 0 270)
			(layer "F.Fab")
			(effects
				(font
					(size 1.27 1.27)
				)
			)
		)
		(duplicate_pad_numbers_are_jumpers no)
		(fp_line
			(start -0.299974 0.150114)
			(end -0.299974 -0.150114)
			(stroke
				(width 0.1)
				(type default)
			)
			(layer "F.Fab")
		)
		(fp_line
			(start 0.299974 0.150114)
			(end -0.299974 0.150114)
			(stroke
				(width 0.1)
				(type default)
			)
			(layer "F.Fab")
		)
		(fp_line
			(start -0.299974 -0.150114)
			(end 0.299974 -0.150114)
			(stroke
				(width 0.1)
				(type default)
			)
			(layer "F.Fab")
		)
		(fp_line
			(start 0.299974 -0.150114)
			(end 0.299974 0.150114)
			(stroke
				(width 0.1)
				(type default)
			)
			(layer "F.Fab")
		)
		(pad "1" smd rect
			(at -0.2667 0 270)
			(size 0.3048 0.381)
			(layers "F.Cu" "F.Mask" "F.Paste")
			(net "P5E_CPU0_PE0_TX_C_DP<2>")
		)
		(pad "2" smd rect
			(at 0.2667 0 270)
			(size 0.3048 0.381)
			(layers "F.Cu" "F.Mask" "F.Paste")
			(net "P5E_CPU0_PE0_TX_DP<2>")
		)
	)
)
